(kicad_pcb
	(version 20260206)
	(generator "pcbnew")
	(generator_version "10.0")
	(general
		(thickness 1.6)
		(legacy_teardrops no)
	)
	(paper "A4")
	(title_block
		(title "03242023_DA0F0TMBIJ0_F0T_Motherboard_J_brd_V01_OCP.brd")
		(comment 1 "Grand Teton / footprints 2605-2609 of 6105")
	)
	(layers
		(0 "F.Cu" signal "TOP")
		(4 "In1.Cu" signal "GND")
		(6 "In2.Cu" signal "IN1")
		(8 "In3.Cu" signal "GND1")
		(10 "In4.Cu" signal "IN2")
		(12 "In5.Cu" signal "GND2")
		(14 "In6.Cu" signal "IN3")
		(16 "In7.Cu" signal "GND3")
		(18 "In8.Cu" signal "VCC")
		(20 "In9.Cu" signal "VCC1")
		(22 "In10.Cu" signal "GND4")
		(24 "In11.Cu" signal "IN4")
		(26 "In12.Cu" signal "GND5")
		(28 "In13.Cu" signal "IN5")
		(30 "In14.Cu" signal "GND6")
		(32 "In15.Cu" signal "IN6")
		(34 "In16.Cu" signal "GND7")
		(2 "B.Cu" signal "BOTTOM")
		(9 "F.Adhes" user "F.Adhesive")
		(11 "B.Adhes" user "B.Adhesive")
		(13 "F.Paste" user "Package Geometry/Pastemask Top")
		(15 "B.Paste" user "Package Geometry/Pastemask Bottom")
		(5 "F.SilkS" user "Ref Des/Silkscreen Top")
		(7 "B.SilkS" user "Ref Des/Silkscreen Bottom")
		(1 "F.Mask" user "Board Geometry/Soldermask Top")
		(3 "B.Mask" user "Board Geometry/Soldermask Bottom")
		(17 "Dwgs.User" user "User.Drawings")
		(19 "Cmts.User" user "User.Comments")
		(21 "Eco1.User" user "User.Eco1")
		(23 "Eco2.User" user "User.Eco2")
		(25 "Edge.Cuts" user "Board Geometry/Outline")
		(27 "Margin" user)
		(31 "F.CrtYd" user "Package Geometry/Place Bound Top")
		(29 "B.CrtYd" user "Package Geometry/Place Bound Bottom")
		(35 "F.Fab" user "Ref Des/Assembly Top")
		(33 "B.Fab" user "Ref Des/Assembly Bottom")
	)
	(footprint ""
		(layer "F.Cu")
		(at 173.216062 -29.430472)
		(property "Reference" "R3836"
			(at 0 0 0)
			(layer "F.SilkS")
			(hide yes)
			(effects
				(font
					(size 1.27 1.27)
				)
			)
		)
		(property "Value" ""
			(at 0 0 0)
			(layer "F.Fab")
			(effects
				(font
					(size 1.27 1.27)
				)
			)
		)
		(duplicate_pad_numbers_are_jumpers no)
		(fp_line
			(start -0.7874 -0.4064)
			(end 0.7874 -0.4064)
			(stroke
				(width 0.1524)
				(type default)
			)
			(layer "F.SilkS")
		)
		(fp_line
			(start -0.7874 0.4064)
			(end -0.7874 -0.4064)
			(stroke
				(width 0.1524)
				(type default)
			)
			(layer "F.SilkS")
		)
		(fp_line
			(start 0.7874 -0.4064)
			(end 0.7874 0.4064)
			(stroke
				(width 0.1524)
				(type default)
			)
			(layer "F.SilkS")
		)
		(fp_line
			(start 0.7874 0.4064)
			(end -0.7874 0.4064)
			(stroke
				(width 0.1524)
				(type default)
			)
			(layer "F.SilkS")
		)
		(fp_line
			(start -0.67945 -0.305054)
			(end -0.12065 -0.305054)
			(stroke
				(width 0.1)
				(type default)
			)
			(layer "F.Fab")
		)
		(fp_line
			(start -0.67945 0.3048)
			(end -0.67945 -0.305054)
			(stroke
				(width 0.1)
				(type default)
			)
			(layer "F.Fab")
		)
		(fp_line
			(start -0.12065 -0.305054)
			(end -0.12065 -0.2794)
			(stroke
				(width 0.1)
				(type default)
			)
			(layer "F.Fab")
		)
		(fp_line
			(start -0.12065 -0.2794)
			(end 0.12065 -0.2794)
			(stroke
				(width 0.1)
				(type default)
			)
			(layer "F.Fab")
		)
		(fp_line
			(start -0.12065 0.2794)
			(end -0.12065 0.3048)
			(stroke
				(width 0.1)
				(type default)
			)
			(layer "F.Fab")
		)
		(fp_line
			(start -0.12065 0.3048)
			(end -0.67945 0.3048)
			(stroke
				(width 0.1)
				(type default)
			)
			(layer "F.Fab")
		)
		(fp_line
			(start 0.120396 0.2794)
			(end -0.12065 0.2794)
			(stroke
				(width 0.1)
				(type default)
			)
			(layer "F.Fab")
		)
		(fp_line
			(start 0.120396 0.3048)
			(end 0.120396 0.2794)
			(stroke
				(width 0.1)
				(type default)
			)
			(layer "F.Fab")
		)
		(fp_line
			(start 0.12065 -0.3048)
			(end 0.67945 -0.3048)
			(stroke
				(width 0.1)
				(type default)
			)
			(layer "F.Fab")
		)
		(fp_line
			(start 0.12065 -0.2794)
			(end 0.12065 -0.3048)
			(stroke
				(width 0.1)
				(type default)
			)
			(layer "F.Fab")
		)
		(fp_line
			(start 0.67945 -0.3048)
			(end 0.67945 0.3048)
			(stroke
				(width 0.1)
				(type default)
			)
			(layer "F.Fab")
		)
		(fp_line
			(start 0.67945 0.3048)
			(end 0.120396 0.3048)
			(stroke
				(width 0.1)
				(type default)
			)
			(layer "F.Fab")
		)
		(pad "1" smd circle
			(at -0.40005 0)
			(size 0 0)
			(layers "F.Cu" "F.Mask" "F.Paste")
			(net "P3V3_AUX")
		)
		(pad "2" smd circle
			(at 0.40005 0)
			(size 0 0)
			(layers "F.Cu" "F.Mask" "F.Paste")
			(net "HP_LVC3_SCM_HSC_PWRGD_R")
		)
	)
	(footprint ""
		(layer "F.Cu")
		(at 209.35188 -108.422948 90)
		(property "Reference" "R2339"
			(at 0 0 90)
			(layer "F.SilkS")
			(hide yes)
			(effects
				(font
					(size 1.27 1.27)
				)
			)
		)
		(property "Value" ""
			(at 0 0 90)
			(layer "F.Fab")
			(effects
				(font
					(size 1.27 1.27)
				)
			)
		)
		(duplicate_pad_numbers_are_jumpers no)
		(fp_line
			(start 0.7874 -0.4064)
			(end 0.7874 0.4064)
			(stroke
				(width 0.1524)
				(type default)
			)
			(layer "F.SilkS")
		)
		(fp_line
			(start -0.7874 -0.4064)
			(end 0.7874 -0.4064)
			(stroke
				(width 0.1524)
				(type default)
			)
			(layer "F.SilkS")
		)
		(fp_line
			(start 0.7874 0.4064)
			(end -0.7874 0.4064)
			(stroke
				(width 0.1524)
				(type default)
			)
			(layer "F.SilkS")
		)
		(fp_line
			(start -0.7874 0.4064)
			(end -0.7874 -0.4064)
			(stroke
				(width 0.1524)
				(type default)
			)
			(layer "F.SilkS")
		)
		(fp_line
			(start -0.12065 -0.305054)
			(end -0.12065 -0.2794)
			(stroke
				(width 0.1)
				(type default)
			)
			(layer "F.Fab")
		)
		(fp_line
			(start -0.67945 -0.305054)
			(end -0.12065 -0.305054)
			(stroke
				(width 0.1)
				(type default)
			)
			(layer "F.Fab")
		)
		(fp_line
			(start 0.67945 -0.3048)
			(end 0.67945 0.3048)
			(stroke
				(width 0.1)
				(type default)
			)
			(layer "F.Fab")
		)
		(fp_line
			(start 0.12065 -0.3048)
			(end 0.67945 -0.3048)
			(stroke
				(width 0.1)
				(type default)
			)
			(layer "F.Fab")
		)
		(fp_line
			(start 0.12065 -0.2794)
			(end 0.12065 -0.3048)
			(stroke
				(width 0.1)
				(type default)
			)
			(layer "F.Fab")
		)
		(fp_line
			(start -0.12065 -0.2794)
			(end 0.12065 -0.2794)
			(stroke
				(width 0.1)
				(type default)
			)
			(layer "F.Fab")
		)
		(fp_line
			(start 0.120396 0.2794)
			(end -0.12065 0.2794)
			(stroke
				(width 0.1)
				(type default)
			)
			(layer "F.Fab")
		)
		(fp_line
			(start -0.12065 0.2794)
			(end -0.12065 0.3048)
			(stroke
				(width 0.1)
				(type default)
			)
			(layer "F.Fab")
		)
		(fp_line
			(start 0.67945 0.3048)
			(end 0.120396 0.3048)
			(stroke
				(width 0.1)
				(type default)
			)
			(layer "F.Fab")
		)
		(fp_line
			(start 0.120396 0.3048)
			(end 0.120396 0.2794)
			(stroke
				(width 0.1)
				(type default)
			)
			(layer "F.Fab")
		)
		(fp_line
			(start -0.12065 0.3048)
			(end -0.67945 0.3048)
			(stroke
				(width 0.1)
				(type default)
			)
			(layer "F.Fab")
		)
		(fp_line
			(start -0.67945 0.3048)
			(end -0.67945 -0.305054)
			(stroke
				(width 0.1)
				(type default)
			)
			(layer "F.Fab")
		)
		(pad "1" smd circle
			(at -0.40005 0 90)
			(size 0 0)
			(layers "F.Cu" "F.Mask" "F.Paste")
			(net "LED_CPU_RMCA_CATERR_R")
		)
		(pad "2" smd circle
			(at 0.40005 0 90)
			(size 0 0)
			(layers "F.Cu" "F.Mask" "F.Paste")
			(net "GND")
		)
	)
	(footprint ""
		(layer "F.Cu")
		(at 191.861186 -438.17413 -90)
		(property "Reference" "R3770"
			(at 0 0 270)
			(layer "F.SilkS")
			(hide yes)
			(effects
				(font
					(size 1.27 1.27)
				)
			)
		)
		(property "Value" ""
			(at 0 0 270)
			(layer "F.Fab")
			(effects
				(font
					(size 1.27 1.27)
				)
			)
		)
		(duplicate_pad_numbers_are_jumpers no)
		(fp_line
			(start -0.7874 0.4064)
			(end -0.7874 -0.4064)
			(stroke
				(width 0.1524)
				(type default)
			)
			(layer "F.SilkS")
		)
		(fp_line
			(start 0.7874 0.4064)
			(end -0.7874 0.4064)
			(stroke
				(width 0.1524)
				(type default)
			)
			(layer "F.SilkS")
		)
		(fp_line
			(start -0.7874 -0.4064)
			(end 0.7874 -0.4064)
			(stroke
				(width 0.1524)
				(type default)
			)
			(layer "F.SilkS")
		)
		(fp_line
			(start 0.7874 -0.4064)
			(end 0.7874 0.4064)
			(stroke
				(width 0.1524)
				(type default)
			)
			(layer "F.SilkS")
		)
		(fp_line
			(start -0.67945 0.3048)
			(end -0.67945 -0.305054)
			(stroke
				(width 0.1)
				(type default)
			)
			(layer "F.Fab")
		)
		(fp_line
			(start -0.12065 0.3048)
			(end -0.67945 0.3048)
			(stroke
				(width 0.1)
				(type default)
			)
			(layer "F.Fab")
		)
		(fp_line
			(start 0.120396 0.3048)
			(end 0.120396 0.2794)
			(stroke
				(width 0.1)
				(type default)
			)
			(layer "F.Fab")
		)
		(fp_line
			(start 0.67945 0.3048)
			(end 0.120396 0.3048)
			(stroke
				(width 0.1)
				(type default)
			)
			(layer "F.Fab")
		)
		(fp_line
			(start -0.12065 0.2794)
			(end -0.12065 0.3048)
			(stroke
				(width 0.1)
				(type default)
			)
			(layer "F.Fab")
		)
		(fp_line
			(start 0.120396 0.2794)
			(end -0.12065 0.2794)
			(stroke
				(width 0.1)
				(type default)
			)
			(layer "F.Fab")
		)
		(fp_line
			(start -0.12065 -0.2794)
			(end 0.12065 -0.2794)
			(stroke
				(width 0.1)
				(type default)
			)
			(layer "F.Fab")
		)
		(fp_line
			(start 0.12065 -0.2794)
			(end 0.12065 -0.3048)
			(stroke
				(width 0.1)
				(type default)
			)
			(layer "F.Fab")
		)
		(fp_line
			(start 0.12065 -0.3048)
			(end 0.67945 -0.3048)
			(stroke
				(width 0.1)
				(type default)
			)
			(layer "F.Fab")
		)
		(fp_line
			(start 0.67945 -0.3048)
			(end 0.67945 0.3048)
			(stroke
				(width 0.1)
				(type default)
			)
			(layer "F.Fab")
		)
		(fp_line
			(start -0.67945 -0.305054)
			(end -0.12065 -0.305054)
			(stroke
				(width 0.1)
				(type default)
			)
			(layer "F.Fab")
		)
		(fp_line
			(start -0.12065 -0.305054)
			(end -0.12065 -0.2794)
			(stroke
				(width 0.1)
				(type default)
			)
			(layer "F.Fab")
		)
		(pad "1" smd circle
			(at -0.40005 0 270)
			(size 0 0)
			(layers "F.Cu" "F.Mask" "F.Paste")
			(net "GPU_PRSNT")
		)
		(pad "2" smd circle
			(at 0.40005 0 270)
			(size 0 0)
			(layers "F.Cu" "F.Mask" "F.Paste")
			(net "GPU_PRSNT_R")
		)
	)
	(footprint ""
		(layer "F.Cu")
		(at 160.28035 -44.632626 90)
		(property "Reference" "R4474"
			(at 0 0 90)
			(layer "F.SilkS")
			(hide yes)
			(effects
				(font
					(size 1.27 1.27)
				)
			)
		)
		(property "Value" ""
			(at 0 0 90)
			(layer "F.Fab")
			(effects
				(font
					(size 1.27 1.27)
				)
			)
		)
		(duplicate_pad_numbers_are_jumpers no)
		(fp_line
			(start 0.7874 0.4064)
			(end -0.7874 0.4064)
			(stroke
				(width 0.1524)
				(type default)
			)
			(layer "F.SilkS")
		)
		(fp_line
			(start -0.7874 0.4064)
			(end -0.7874 -0.4064)
			(stroke
				(width 0.1524)
				(type default)
			)
			(layer "F.SilkS")
		)
		(fp_line
			(start -0.12065 -0.305054)
			(end -0.12065 -0.2794)
			(stroke
				(width 0.1)
				(type default)
			)
			(layer "F.Fab")
		)
		(fp_line
			(start -0.67945 -0.305054)
			(end -0.12065 -0.305054)
			(stroke
				(width 0.1)
				(type default)
			)
			(layer "F.Fab")
		)
		(fp_line
			(start 0.67945 -0.3048)
			(end 0.67945 0.3048)
			(stroke
				(width 0.1)
				(type default)
			)
			(layer "F.Fab")
		)
		(fp_line
			(start 0.12065 -0.3048)
			(end 0.67945 -0.3048)
			(stroke
				(width 0.1)
				(type default)
			)
			(layer "F.Fab")
		)
		(fp_line
			(start 0.12065 -0.2794)
			(end 0.12065 -0.3048)
			(stroke
				(width 0.1)
				(type default)
			)
			(layer "F.Fab")
		)
		(fp_line
			(start -0.12065 -0.2794)
			(end 0.12065 -0.2794)
			(stroke
				(width 0.1)
				(type default)
			)
			(layer "F.Fab")
		)
		(fp_line
			(start 0.120396 0.2794)
			(end -0.12065 0.2794)
			(stroke
				(width 0.1)
				(type default)
			)
			(layer "F.Fab")
		)
		(fp_line
			(start -0.12065 0.2794)
			(end -0.12065 0.3048)
			(stroke
				(width 0.1)
				(type default)
			)
			(layer "F.Fab")
		)
		(fp_line
			(start 0.67945 0.3048)
			(end 0.120396 0.3048)
			(stroke
				(width 0.1)
				(type default)
			)
			(layer "F.Fab")
		)
		(fp_line
			(start 0.120396 0.3048)
			(end 0.120396 0.2794)
			(stroke
				(width 0.1)
				(type default)
			)
			(layer "F.Fab")
		)
		(fp_line
			(start -0.12065 0.3048)
			(end -0.67945 0.3048)
			(stroke
				(width 0.1)
				(type default)
			)
			(layer "F.Fab")
		)
		(fp_line
			(start -0.67945 0.3048)
			(end -0.67945 -0.305054)
			(stroke
				(width 0.1)
				(type default)
			)
			(layer "F.Fab")
		)
		(pad "1" smd rect
			(at -0.40005 0 270)
			(size 0.4572 0.508)
			(layers "F.Cu" "F.Mask" "F.Paste")
			(net "USB2_0_DN")
		)
		(pad "2" smd rect
			(at 0.40005 0 270)
			(size 0.4572 0.508)
			(layers "F.Cu" "F.Mask" "F.Paste")
			(net "USB2_HOST_PCH_0_DN")
		)
	)
	(footprint ""
		(layer "F.Cu")
		(at 80.67675 -342.917018)
		(property "Reference" "PU24_P1_7"
			(at -11.33475 4.14274 0)
			(unlocked yes)
			(layer "F.SilkS")
			(effects
				(font
					(size 0.7874 0.5842)
					(thickness 0.1524)
				)
				(justify left)
			)
		)
		(property "Value" ""
			(at 0 0 0)
			(layer "F.Fab")
			(effects
				(font
					(size 1.27 1.27)
				)
			)
		)
		(duplicate_pad_numbers_are_jumpers no)
		(fp_line
			(start -2.500122 -2.999994)
			(end -2.24409 -2.999994)
			(stroke
				(width 0.1524)
				(type default)
			)
			(layer "F.SilkS")
		)
		(fp_line
			(start -2.500122 -2.529078)
			(end -2.500122 -2.999994)
			(stroke
				(width 0.1524)
				(type default)
			)
			(layer "F.SilkS")
		)
		(fp_line
			(start -2.500122 0.6604)
			(end -2.500122 0.229108)
			(stroke
				(width 0.1524)
				(type default)
			)
			(layer "F.SilkS")
		)
		(fp_line
			(start -2.500122 2.999994)
			(end -2.500122 2.339594)
			(stroke
				(width 0.1524)
				(type default)
			)
			(layer "F.SilkS")
		)
		(fp_line
			(start -2.2987 2.999994)
			(end -2.500122 2.999994)
			(stroke
				(width 0.1524)
				(type default)
			)
			(layer "F.SilkS")
		)
		(fp_line
			(start 2.31394 -2.999994)
			(end 2.500122 -2.999994)
			(stroke
				(width 0.1524)
				(type default)
			)
			(layer "F.SilkS")
		)
		(fp_line
			(start 2.500122 -2.999994)
			(end 2.500122 -2.44348)
			(stroke
				(width 0.1524)
				(type default)
			)
			(layer "F.SilkS")
		)
		(fp_line
			(start 2.500122 2.339594)
			(end 2.500122 2.999994)
			(stroke
				(width 0.1524)
				(type default)
			)
			(layer "F.SilkS")
		)
		(fp_line
			(start 2.500122 2.999994)
			(end 2.2987 2.999994)
			(stroke
				(width 0.1524)
				(type default)
			)
			(layer "F.SilkS")
		)
		(fp_poly
			(pts
				(xy -3.36423 -3.401822) (xy -2.648712 -2.831592) (xy -2.622296 -3.736594)
			)
			(stroke
				(width 0)
				(type default)
			)
			(fill yes)
			(layer "F.SilkS")
		)
		(fp_line
			(start -2.500122 -2.999994)
			(end 2.500122 -2.999994)
			(stroke
				(width 0.1)
				(type default)
			)
			(layer "F.Fab")
		)
		(fp_line
			(start -2.500122 2.999994)
			(end -2.500122 -2.999994)
			(stroke
				(width 0.1)
				(type default)
			)
			(layer "F.Fab")
		)
		(fp_line
			(start 2.500122 -2.999994)
			(end 2.500122 2.999994)
			(stroke
				(width 0.1)
				(type default)
			)
			(layer "F.Fab")
		)
		(fp_line
			(start 2.500122 2.999994)
			(end -2.500122 2.999994)
			(stroke
				(width 0.1)
				(type default)
			)
			(layer "F.Fab")
		)
		(fp_poly
			(pts
				(xy -4.218432 -2.783078) (xy -4.218432 -1.767078) (xy -3.202432 -2.275078)
			)
			(stroke
				(width 0)
				(type default)
			)
			(fill yes)
			(layer "F.Fab")
		)
		(pad "1" smd rect
			(at -2.400046 -2.275078 90)
			(size 0.2286 0.6096)
			(layers "F.Cu" "F.Mask" "F.Paste")
			(net "PVCCIN_CPU1_VOS7")
		)
		(pad "2" smd rect
			(at -2.400046 -1.82499 90)
			(size 0.2286 0.6096)
			(layers "F.Cu" "F.Mask" "F.Paste")
			(net "GND")
		)
		(pad "3" smd rect
			(at -2.400046 -1.374902 90)
			(size 0.2286 0.6096)
			(layers "F.Cu" "F.Mask" "F.Paste")
			(net "PVCCIN_CPU1_VDD7")
		)
		(pad "4" smd rect
			(at -2.400046 -0.925068 90)
			(size 0.2286 0.6096)
			(layers "F.Cu" "F.Mask" "F.Paste")
			(net "PVCCIN_CPU1_PVCC")
		)
		(pad "5" smd rect
			(at -2.400046 -0.47498 90)
			(size 0.2286 0.6096)
			(layers "F.Cu" "F.Mask" "F.Paste")
			(net "GND")
		)
		(pad "6" smd rect
			(at -2.400046 -0.024892 90)
			(size 0.2286 0.6096)
			(layers "F.Cu" "F.Mask" "F.Paste")
			(net "Net_8538")
		)
		(pad "7_9-20_24" smd circle
			(at 0 1.150112 90)
			(size 0 0)
			(layers "F.Cu" "F.Mask" "F.Paste")
			(net "GND")
		)
		(pad "10_19" smd rect
			(at 0 2.899918 90)
			(size 0.6096 4.318)
			(layers "F.Cu" "F.Mask" "F.Paste")
			(net "SW_PVCCIN_CPU1_SW7")
		)
		(pad "25_29" smd rect
			(at 1.549908 -1.279906 270)
			(size 2.0574 2.3114)
			(layers "F.Cu" "F.Mask" "F.Paste")
			(net "SW_P12V_PVCCIN_CPU1_FLT")
		)
		(pad "30" smd rect
			(at 2.05994 -2.899918)
			(size 0.2286 0.6096)
			(layers "F.Cu" "F.Mask" "F.Paste")
			(net "SW_P12V_PVCCIN_CPU1_FLT")
		)
		(pad "31" smd rect
			(at 1.610106 -2.899918)
			(size 0.2286 0.6096)
			(layers "F.Cu" "F.Mask" "F.Paste")
			(net "Net_8539")
		)
		(pad "32" smd rect
			(at 1.160018 -2.899918)
			(size 0.2286 0.6096)
			(layers "F.Cu" "F.Mask" "F.Paste")
			(net "SW_PVCCIN_CPU1_BOOTR7")
		)
		(pad "33" smd rect
			(at 0.70993 -2.899918)
			(size 0.2286 0.6096)
			(layers "F.Cu" "F.Mask" "F.Paste")
			(net "SW_PVCCIN_CPU1_BOOT7")
		)
		(pad "34" smd rect
			(at 0.260096 -2.899918)
			(size 0.2286 0.6096)
			(layers "F.Cu" "F.Mask" "F.Paste")
			(net "PVCCIN_CPU1_PWM7")
		)
		(pad "35" smd rect
			(at -0.189992 -2.899918)
			(size 0.2286 0.6096)
			(layers "F.Cu" "F.Mask" "F.Paste")
			(net "PVCCIN_CPU1_VDD7")
		)
		(pad "36" smd rect
			(at -0.64008 -2.899918)
			(size 0.2286 0.6096)
			(layers "F.Cu" "F.Mask" "F.Paste")
			(net "PVCCIN_CPU1_ATSEN")
		)
		(pad "37" smd rect
			(at -1.089914 -2.899918)
			(size 0.2286 0.6096)
			(layers "F.Cu" "F.Mask" "F.Paste")
			(net "PVCCIN_CPU1_LSET7")
		)
		(pad "38" smd rect
			(at -1.540002 -2.899918)
			(size 0.2286 0.6096)
			(layers "F.Cu" "F.Mask" "F.Paste")
			(net "PVCCIN_CPU1_IMON7")
		)
		(pad "39" smd rect
			(at -1.99009 -2.899918)
			(size 0.2286 0.6096)
			(layers "F.Cu" "F.Mask" "F.Paste")
			(net "PVCCIN_CPU1_VREF")
		)
		(pad "40" smd rect
			(at -0.87503 -1.27508)
			(size 1.7526 1.9558)
			(layers "F.Cu" "F.Mask" "F.Paste")
			(net "GND")
		)
		(pad "41" smd rect
			(at -1.525016 0.249936 270)
			(size 0.3048 0.4572)
			(layers "F.Cu" "F.Mask" "F.Paste")
			(net "Net_8537")
		)
		(zone
			(layer "F.Cu")
			(hatch none 0.5)
			(connect_pads
				(clearance 0)
			)
			(min_thickness 0.25)
			(keepout
				(tracks not_allowed)
				(vias allowed)
				(pads allowed)
				(copperpour not_allowed)
				(footprints allowed)
			)
			(placement
				(enabled no)
				(sheetname "")
			)
			(fill
				(thermal_gap 0.5)
				(thermal_bridge_width 0.5)
				(island_removal_mode 0)
			)
			(polygon
				(pts
					(xy 78.176628 -339.917024) (xy 78.176628 -340.666324) (xy 83.176872 -340.666324) (xy 83.176872 -339.917024)
					(xy 82.9691 -339.917024) (xy 82.9691 -340.23427) (xy 82.88655 -340.31682) (xy 82.88655 -340.3727)
					(xy 78.46695 -340.3727) (xy 78.46695 -340.24316) (xy 78.41488 -340.19109) (xy 78.41488 -339.917024)
				)
			)
		)
	)
)
